# SCM (Grand Teton) — schematic netlist excerpt (pin names and nets, part order shuffled) for the footprints in the layout excerpt that follows; sources: Cadence DE-HDL packaged netlist, KiCad conversion of 12092022_DA0F0TMDCD0_F0T_Management_Board_D_brd_V3_OCP.brd

R226  Q_RES  10K 1% CHIP  pkg 0402LF  page 32 : A = P3V3_AUX ; B = JTAG_MB_TDI
R9  Q_RES  4.7K 1% CHIP  pkg 0402LF  page 20 : A = M_BMC_DDR4_ALERT_N ; B = P1V2_AUX

(kicad_pcb
	(version 20260206)
	(generator "pcbnew")
	(generator_version "10.0")
	(general
		(thickness 1.6)
		(legacy_teardrops no)
	)
	(paper "A4")
	(title_block
		(title "12092022_DA0F0TMDCD0_F0T_Management_Board_D_brd_V3_OCP.brd")
		(comment 1 "Grand Teton / footprints 1343-1344 of 1440")
	)
	(layers
		(0 "F.Cu" signal "TOP")
		(4 "In1.Cu" signal "GND")
		(6 "In2.Cu" signal "IN1")
		(8 "In3.Cu" signal "GND1")
		(10 "In4.Cu" signal "IN2")
		(12 "In5.Cu" signal "VCC")
		(14 "In6.Cu" signal "VCC1")
		(16 "In7.Cu" signal "IN3")
		(18 "In8.Cu" signal "GND2")
		(20 "In9.Cu" signal "IN4")
		(22 "In10.Cu" signal "GND3")
		(2 "B.Cu" signal "BOTTOM")
		(9 "F.Adhes" user "F.Adhesive")
		(11 "B.Adhes" user "B.Adhesive")
		(13 "F.Paste" user "Package Geometry/Pastemask Top")
		(15 "B.Paste" user "Package Geometry/Pastemask Bottom")
		(5 "F.SilkS" user "Ref Des/Silkscreen Top")
		(7 "B.SilkS" user "Ref Des/Silkscreen Bottom")
		(1 "F.Mask" user "Board Geometry/Soldermask Top")
		(3 "B.Mask" user "Board Geometry/Soldermask Bottom")
		(17 "Dwgs.User" user "User.Drawings")
		(19 "Cmts.User" user "User.Comments")
		(21 "Eco1.User" user "User.Eco1")
		(23 "Eco2.User" user "User.Eco2")
		(25 "Edge.Cuts" user "Board Geometry/Outline")
		(27 "Margin" user)
		(31 "F.CrtYd" user "Package Geometry/Place Bound Top")
		(29 "B.CrtYd" user "Package Geometry/Place Bound Bottom")
		(35 "F.Fab" user "Ref Des/Assembly Top")
		(33 "B.Fab" user "Ref Des/Assembly Bottom")
	)
	(footprint ""
		(layer "B.Cu")
		(at 37.084 -106.3625 -90)
		(property "Reference" "R226"
			(at 0 0 90)
			(layer "B.SilkS")
			(hide yes)
			(effects
				(font
					(size 1.27 1.27)
				)
				(justify mirror)
			)
		)
		(property "Value" ""
			(at 0 0 90)
			(layer "B.Fab")
			(effects
				(font
					(size 1.27 1.27)
				)
				(justify mirror)
			)
		)
		(duplicate_pad_numbers_are_jumpers no)
		(fp_line
			(start -0.7874 0.4064)
			(end 0.7874 0.4064)
			(stroke
				(width 0.1524)
				(type default)
			)
			(layer "B.SilkS")
		)
		(fp_line
			(start 0.7874 0.4064)
			(end 0.7874 -0.4064)
			(stroke
				(width 0.1524)
				(type default)
			)
			(layer "B.SilkS")
		)
		(fp_line
			(start -0.7874 -0.4064)
			(end -0.7874 0.4064)
			(stroke
				(width 0.1524)
				(type default)
			)
			(layer "B.SilkS")
		)
		(fp_line
			(start 0.7874 -0.4064)
			(end -0.7874 -0.4064)
			(stroke
				(width 0.1524)
				(type default)
			)
			(layer "B.SilkS")
		)
		(fp_line
			(start -0.67945 0.3048)
			(end -0.120396 0.3048)
			(stroke
				(width 0.1)
				(type default)
			)
			(layer "B.Fab")
		)
		(fp_line
			(start -0.120396 0.3048)
			(end -0.120396 0.2794)
			(stroke
				(width 0.1)
				(type default)
			)
			(layer "B.Fab")
		)
		(fp_line
			(start 0.12065 0.3048)
			(end 0.67945 0.3048)
			(stroke
				(width 0.1)
				(type default)
			)
			(layer "B.Fab")
		)
		(fp_line
			(start 0.67945 0.3048)
			(end 0.67945 -0.305054)
			(stroke
				(width 0.1)
				(type default)
			)
			(layer "B.Fab")
		)
		(fp_line
			(start -0.120396 0.2794)
			(end 0.12065 0.2794)
			(stroke
				(width 0.1)
				(type default)
			)
			(layer "B.Fab")
		)
		(fp_line
			(start 0.12065 0.2794)
			(end 0.12065 0.3048)
			(stroke
				(width 0.1)
				(type default)
			)
			(layer "B.Fab")
		)
		(fp_line
			(start -0.12065 -0.2794)
			(end -0.12065 -0.3048)
			(stroke
				(width 0.1)
				(type default)
			)
			(layer "B.Fab")
		)
		(fp_line
			(start 0.12065 -0.2794)
			(end -0.12065 -0.2794)
			(stroke
				(width 0.1)
				(type default)
			)
			(layer "B.Fab")
		)
		(fp_line
			(start -0.67945 -0.3048)
			(end -0.67945 0.3048)
			(stroke
				(width 0.1)
				(type default)
			)
			(layer "B.Fab")
		)
		(fp_line
			(start -0.12065 -0.3048)
			(end -0.67945 -0.3048)
			(stroke
				(width 0.1)
				(type default)
			)
			(layer "B.Fab")
		)
		(fp_line
			(start 0.12065 -0.305054)
			(end 0.12065 -0.2794)
			(stroke
				(width 0.1)
				(type default)
			)
			(layer "B.Fab")
		)
		(fp_line
			(start 0.67945 -0.305054)
			(end 0.12065 -0.305054)
			(stroke
				(width 0.1)
				(type default)
			)
			(layer "B.Fab")
		)
		(pad "1" smd circle
			(at 0.40005 0 90)
			(size 0 0)
			(layers "B.Cu" "B.Mask" "B.Paste")
			(net "P3V3_AUX")
		)
		(pad "2" smd circle
			(at -0.40005 0 90)
			(size 0 0)
			(layers "B.Cu" "B.Mask" "B.Paste")
			(net "JTAG_MB_TDI")
		)
	)
	(footprint ""
		(layer "B.Cu")
		(at 83.16722 -43.538394 180)
		(property "Reference" "R9"
			(at 0 0 0)
			(layer "B.SilkS")
			(hide yes)
			(effects
				(font
					(size 1.27 1.27)
				)
				(justify mirror)
			)
		)
		(property "Value" ""
			(at 0 0 0)
			(layer "B.Fab")
			(effects
				(font
					(size 1.27 1.27)
				)
				(justify mirror)
			)
		)
		(duplicate_pad_numbers_are_jumpers no)
		(fp_line
			(start 0.7874 0.4064)
			(end 0.7874 -0.4064)
			(stroke
				(width 0.1524)
				(type default)
			)
			(layer "B.SilkS")
		)
		(fp_line
			(start 0.7874 -0.4064)
			(end -0.7874 -0.4064)
			(stroke
				(width 0.1524)
				(type default)
			)
			(layer "B.SilkS")
		)
		(fp_line
			(start -0.7874 0.4064)
			(end 0.7874 0.4064)
			(stroke
				(width 0.1524)
				(type default)
			)
			(layer "B.SilkS")
		)
		(fp_line
			(start -0.7874 -0.4064)
			(end -0.7874 0.4064)
			(stroke
				(width 0.1524)
				(type default)
			)
			(layer "B.SilkS")
		)
		(fp_line
			(start 0.67945 0.3048)
			(end 0.67945 -0.305054)
			(stroke
				(width 0.1)
				(type default)
			)
			(layer "B.Fab")
		)
		(fp_line
			(start 0.67945 -0.305054)
			(end 0.12065 -0.305054)
			(stroke
				(width 0.1)
				(type default)
			)
			(layer "B.Fab")
		)
		(fp_line
			(start 0.12065 0.3048)
			(end 0.67945 0.3048)
			(stroke
				(width 0.1)
				(type default)
			)
			(layer "B.Fab")
		)
		(fp_line
			(start 0.12065 0.2794)
			(end 0.12065 0.3048)
			(stroke
				(width 0.1)
				(type default)
			)
			(layer "B.Fab")
		)
		(fp_line
			(start 0.12065 -0.2794)
			(end -0.12065 -0.2794)
			(stroke
				(width 0.1)
				(type default)
			)
			(layer "B.Fab")
		)
		(fp_line
			(start 0.12065 -0.305054)
			(end 0.12065 -0.2794)
			(stroke
				(width 0.1)
				(type default)
			)
			(layer "B.Fab")
		)
		(fp_line
			(start -0.120396 0.3048)
			(end -0.120396 0.2794)
			(stroke
				(width 0.1)
				(type default)
			)
			(layer "B.Fab")
		)
		(fp_line
			(start -0.120396 0.2794)
			(end 0.12065 0.2794)
			(stroke
				(width 0.1)
				(type default)
			)
			(layer "B.Fab")
		)
		(fp_line
			(start -0.12065 -0.2794)
			(end -0.12065 -0.3048)
			(stroke
				(width 0.1)
				(type default)
			)
			(layer "B.Fab")
		)
		(fp_line
			(start -0.12065 -0.3048)
			(end -0.67945 -0.3048)
			(stroke
				(width 0.1)
				(type default)
			)
			(layer "B.Fab")
		)
		(fp_line
			(start -0.67945 0.3048)
			(end -0.120396 0.3048)
			(stroke
				(width 0.1)
				(type default)
			)
			(layer "B.Fab")
		)
		(fp_line
			(start -0.67945 -0.3048)
			(end -0.67945 0.3048)
			(stroke
				(width 0.1)
				(type default)
			)
			(layer "B.Fab")
		)
		(pad "1" smd circle
			(at 0.40005 0)
			(size 0 0)
			(layers "B.Cu" "B.Mask" "B.Paste")
			(net "M_BMC_DDR4_ALERT_N")
		)
		(pad "2" smd circle
			(at -0.40005 0)
			(size 0 0)
			(layers "B.Cu" "B.Mask" "B.Paste")
			(net "P1V2_AUX")
		)
	)
)
